# BASEBOARD_FAB2 (Tioga Pass) — schematic netlist excerpt (pin names and nets, part order shuffled) for the footprints in the layout excerpt that follows; sources: Cadence DE-HDL packaged netlist, KiCad conversion of Wiwynn_Tioga_Pass_MB.brd

C6W11  CAP  100UF 4V 20% X5R  pkg 0805  page 221 : A = PVTT_ABC ; B = GND
C25W28  CAP  1.0UF 16V 10% X6S  pkg 0402  page 149 : A = P1V15_AUX_BMC ; B = GND
R4C1  RES  100.0 1% CHIP  pkg 0402  page 205 : A = VSENSE_PVSA_CPU0_N ; B = GND

(kicad_pcb
	(version 20260206)
	(generator "pcbnew")
	(generator_version "10.0")
	(general
		(thickness 1.6)
		(legacy_teardrops no)
	)
	(paper "A4")
	(title_block
		(title "Wiwynn_Tioga_Pass_MB.brd")
		(comment 1 "Tioga Pass / footprints 3855-3857 of 4770")
	)
	(layers
		(0 "F.Cu" signal "TOP")
		(4 "In1.Cu" signal "L2GND")
		(6 "In2.Cu" signal "L3")
		(8 "In3.Cu" signal "L4GND")
		(10 "In4.Cu" signal "L5")
		(12 "In5.Cu" signal "L6GND")
		(14 "In6.Cu" signal "L7VCC")
		(16 "In7.Cu" signal "L8VCC")
		(18 "In8.Cu" signal "L9GND")
		(20 "In9.Cu" signal "L10")
		(22 "In10.Cu" signal "L11GND")
		(24 "In11.Cu" signal "L12")
		(26 "In12.Cu" signal "L13GND")
		(2 "B.Cu" signal "BOTTOM")
		(9 "F.Adhes" user "F.Adhesive")
		(11 "B.Adhes" user "B.Adhesive")
		(13 "F.Paste" user "Package Geometry/Pastemask Top")
		(15 "B.Paste" user "Package Geometry/Pastemask Bottom")
		(5 "F.SilkS" user "Ref Des/Silkscreen Top")
		(7 "B.SilkS" user "Ref Des/Silkscreen Bottom")
		(1 "F.Mask" user "Board Geometry/Soldermask Top")
		(3 "B.Mask" user "Board Geometry/Soldermask Bottom")
		(17 "Dwgs.User" user "User.Drawings")
		(19 "Cmts.User" user "User.Comments")
		(21 "Eco1.User" user "User.Eco1")
		(23 "Eco2.User" user "User.Eco2")
		(25 "Edge.Cuts" user "Board Geometry/Outline")
		(27 "Margin" user)
		(31 "F.CrtYd" user "Package Geometry/Place Bound Top")
		(29 "B.CrtYd" user "Package Geometry/Place Bound Bottom")
		(35 "F.Fab" user "Ref Des/Assembly Top")
		(33 "B.Fab" user "Ref Des/Assembly Bottom")
	)
	(footprint ""
		(layer "B.Cu")
		(at 228.1174 -87.5792 90)
		(property "Reference" "R4C1"
			(at 0.8382 -0.67818 90)
			(unlocked yes)
			(layer "B.SilkS")
			(effects
				(font
					(size 0.4064 0.254)
					(thickness 0.1524)
				)
				(justify left mirror)
			)
		)
		(property "Value" ""
			(at 0 0 90)
			(layer "B.Fab")
			(effects
				(font
					(size 1.27 1.27)
				)
				(justify mirror)
			)
		)
		(duplicate_pad_numbers_are_jumpers no)
		(fp_poly
			(pts
				(xy 0.2794 -0.1016) (xy -0.2794 -0.1016) (xy -0.2794 0.9906) (xy 0.2794 0.9906)
			)
			(stroke
				(width 0)
				(type default)
			)
			(fill no)
			(layer "B.CrtYd")
		)
		(fp_line
			(start 0.2794 -0.1016)
			(end 0.2794 0.9906)
			(stroke
				(width 0.1)
				(type default)
			)
			(layer "B.Fab")
		)
		(fp_line
			(start -0.2794 -0.1016)
			(end 0.2794 -0.1016)
			(stroke
				(width 0.1)
				(type default)
			)
			(layer "B.Fab")
		)
		(fp_line
			(start 0.2794 0.9906)
			(end -0.2794 0.9906)
			(stroke
				(width 0.1)
				(type default)
			)
			(layer "B.Fab")
		)
		(fp_line
			(start -0.2794 0.9906)
			(end -0.2794 -0.1016)
			(stroke
				(width 0.1)
				(type default)
			)
			(layer "B.Fab")
		)
		(pad "1" smd rect
			(at 0 0 270)
			(size 0.508 0.508)
			(layers "B.Cu" "B.Mask" "B.Paste")
			(net "VSENSE_PVSA_CPU0_N")
		)
		(pad "2" smd rect
			(at 0 0.889 270)
			(size 0.508 0.508)
			(layers "B.Cu" "B.Mask" "B.Paste")
			(net "GND")
		)
		(zone
			(layer "B.Cu")
			(hatch none 0.5)
			(connect_pads
				(clearance 0)
			)
			(min_thickness 0.25)
			(keepout
				(tracks allowed)
				(vias not_allowed)
				(pads allowed)
				(copperpour not_allowed)
				(footprints allowed)
			)
			(placement
				(enabled no)
				(sheetname "")
			)
			(fill
				(thermal_gap 0.5)
				(thermal_bridge_width 0.5)
				(island_removal_mode 0)
			)
			(polygon
				(pts
					(xy 228.3714 -87.8332) (xy 228.3714 -87.3252) (xy 228.7524 -87.3252) (xy 228.7524 -87.8332)
				)
			)
		)
		(zone
			(layer "B.Cu")
			(hatch none 0.5)
			(connect_pads
				(clearance 0)
			)
			(min_thickness 0.25)
			(keepout
				(tracks not_allowed)
				(vias allowed)
				(pads allowed)
				(copperpour not_allowed)
				(footprints allowed)
			)
			(placement
				(enabled no)
				(sheetname "")
			)
			(fill
				(thermal_gap 0.5)
				(thermal_bridge_width 0.5)
				(island_removal_mode 0)
			)
			(polygon
				(pts
					(xy 228.7524 -87.8332) (xy 228.7524 -87.3252) (xy 228.3714 -87.3252) (xy 228.3714 -87.8332)
				)
			)
		)
	)
	(footprint ""
		(layer "B.Cu")
		(at 414.5407 -37.76218)
		(property "Reference" "C25W28"
			(at 0.8382 -0.67818 0)
			(unlocked yes)
			(layer "B.SilkS")
			(effects
				(font
					(size 0.4064 0.254)
					(thickness 0.1524)
				)
				(justify left mirror)
			)
		)
		(property "Value" ""
			(at 0 0 0)
			(layer "B.Fab")
			(effects
				(font
					(size 1.27 1.27)
				)
				(justify mirror)
			)
		)
		(duplicate_pad_numbers_are_jumpers no)
		(fp_poly
			(pts
				(xy -0.3048 -0.1016) (xy -0.3048 0.9906) (xy 0.3048 0.9906) (xy 0.3048 -0.1016)
			)
			(stroke
				(width 0)
				(type default)
			)
			(fill no)
			(layer "B.CrtYd")
		)
		(fp_line
			(start -0.3048 -0.1016)
			(end 0.3048 -0.1016)
			(stroke
				(width 0.1)
				(type default)
			)
			(layer "B.Fab")
		)
		(fp_line
			(start -0.3048 0.9906)
			(end -0.3048 -0.1016)
			(stroke
				(width 0.1)
				(type default)
			)
			(layer "B.Fab")
		)
		(fp_line
			(start 0.3048 -0.1016)
			(end 0.3048 0.9906)
			(stroke
				(width 0.1)
				(type default)
			)
			(layer "B.Fab")
		)
		(fp_line
			(start 0.3048 0.9906)
			(end -0.3048 0.9906)
			(stroke
				(width 0.1)
				(type default)
			)
			(layer "B.Fab")
		)
		(pad "1" smd rect
			(at 0 0 180)
			(size 0.508 0.508)
			(layers "B.Cu" "B.Mask" "B.Paste")
			(net "P1V15_AUX_BMC")
		)
		(pad "2" smd rect
			(at 0 0.889 180)
			(size 0.508 0.508)
			(layers "B.Cu" "B.Mask" "B.Paste")
			(net "GND")
		)
		(zone
			(layer "B.Cu")
			(hatch none 0.5)
			(connect_pads
				(clearance 0)
			)
			(min_thickness 0.25)
			(keepout
				(tracks allowed)
				(vias not_allowed)
				(pads allowed)
				(copperpour not_allowed)
				(footprints allowed)
			)
			(placement
				(enabled no)
				(sheetname "")
			)
			(fill
				(thermal_gap 0.5)
				(thermal_bridge_width 0.5)
				(island_removal_mode 0)
			)
			(polygon
				(pts
					(xy 414.7947 -37.50818) (xy 414.2867 -37.50818) (xy 414.2867 -37.12718) (xy 414.7947 -37.12718)
				)
			)
		)
		(zone
			(layer "B.Cu")
			(hatch none 0.5)
			(connect_pads
				(clearance 0)
			)
			(min_thickness 0.25)
			(keepout
				(tracks not_allowed)
				(vias allowed)
				(pads allowed)
				(copperpour not_allowed)
				(footprints allowed)
			)
			(placement
				(enabled no)
				(sheetname "")
			)
			(fill
				(thermal_gap 0.5)
				(thermal_bridge_width 0.5)
				(island_removal_mode 0)
			)
			(polygon
				(pts
					(xy 414.7947 -37.12718) (xy 414.2867 -37.12718) (xy 414.2867 -37.50818) (xy 414.7947 -37.50818)
				)
			)
		)
	)
	(footprint ""
		(layer "B.Cu")
		(at 184.20842 2.63652 -90)
		(property "Reference" "C6W11"
			(at -1.47828 0.78994 0)
			(unlocked yes)
			(layer "B.SilkS")
			(effects
				(font
					(size 0.4064 0.254)
					(thickness 0.1524)
				)
				(justify mirror)
			)
		)
		(property "Value" ""
			(at 0 0 90)
			(layer "B.Fab")
			(effects
				(font
					(size 1.27 1.27)
				)
				(justify mirror)
			)
		)
		(duplicate_pad_numbers_are_jumpers no)
		(fp_poly
			(pts
				(xy 0.7239 -0.2159) (xy -0.7239 -0.2159) (xy -0.7239 1.9939) (xy 0.7239 1.9939)
			)
			(stroke
				(width 0)
				(type default)
			)
			(fill no)
			(layer "B.CrtYd")
		)
		(fp_line
			(start -0.7239 1.9939)
			(end -0.7239 -0.2159)
			(stroke
				(width 0.1)
				(type default)
			)
			(layer "B.Fab")
		)
		(fp_line
			(start 0.7239 1.9939)
			(end -0.7239 1.9939)
			(stroke
				(width 0.1)
				(type default)
			)
			(layer "B.Fab")
		)
		(fp_line
			(start -0.7239 -0.2159)
			(end 0.7239 -0.2159)
			(stroke
				(width 0.1)
				(type default)
			)
			(layer "B.Fab")
		)
		(fp_line
			(start 0.7239 -0.2159)
			(end 0.7239 1.9939)
			(stroke
				(width 0.1)
				(type default)
			)
			(layer "B.Fab")
		)
		(pad "1" smd rect
			(at 0 0 90)
			(size 1.27 1.016)
			(layers "B.Cu" "B.Mask" "B.Paste")
			(net "PVTT_ABC")
		)
		(pad "2" smd rect
			(at 0 1.778 90)
			(size 1.27 1.016)
			(layers "B.Cu" "B.Mask" "B.Paste")
			(net "GND")
		)
		(zone
			(layer "B.Cu")
			(hatch none 0.5)
			(connect_pads
				(clearance 0)
			)
			(min_thickness 0.25)
			(keepout
				(tracks not_allowed)
				(vias allowed)
				(pads allowed)
				(copperpour not_allowed)
				(footprints allowed)
			)
			(placement
				(enabled no)
				(sheetname "")
			)
			(fill
				(thermal_gap 0.5)
				(thermal_bridge_width 0.5)
				(island_removal_mode 0)
			)
			(polygon
				(pts
					(xy 183.70042 3.27152) (xy 183.70042 2.00152) (xy 182.93842 2.00152) (xy 182.93842 3.27152)
				)
			)
		)
	)
)
